# Bryce Canyon_IOM_IOC_Stackup.xlsx — Storage_PCB_Test_Note (pcb-stackup)
| 編號(Number) | 內容(Item) | 附加檔案(Files) | 附加說明(Description) |
| 1 | Impedance traceability and test |  | 1、板廠在HVM量產階段採用AQL 0.65 正常檢驗水準二級來抽樣，利用Excel範本(PCB_Vendor_PCB_Number(XXXXX-SA)_Impedance_Report_Template_Date.xlsx)在量產階段(HVM 90天後)，不同lot 的量測結果分開於不同的分頁中，記錄其Min, Max, Mean, Median, Sigma, CP, CK, CPK等數值。 2、阻抗CPK的允收條件為 c= 0 (HVM 90天後)；阻抗數值的允收條件為 ±10%(EVT, DVT, PVT,HVM)。 3、阻抗測試條需擺放於折斷邊上。 |
